#ISCELL
  mstr_misc dns *
  *
#ISCELL
  pure_quanta quanta_title_block_c *
  *
#ISCELL
  standard offpage *
  page46_i100
#CELL
  pure_quanta q_cap *
  page46_i102
#CELL
  pure_quanta q_res *
  page46_i104
#CELL
  pure_quanta q_res *
  page46_i105
#CELL
  pure_quanta q_res *
  page46_i106
#ISCELL
  logical_power universal_power *
  page46_i107
#CELL
  pure_quanta q_cap *
  page46_i108
#ISCELL
  logical_power universal_gnd *
  page46_i109
#ISCELL
  logical_power universal_gnd *
  page46_i112
#CELL
  pure_quanta sconn11_9192031111lf *
  page46_i113
#CELL
  pure_quanta q_res *
  page46_i114
#CELL
  pure_quanta q_res *
  page46_i115
#CELL
  pure_quanta q_res *
  page46_i116
#CELL
  pure_quanta q_res *
  page46_i117
#CELL
  pure_quanta q_res *
  page46_i119
#ISCELL
  standard offpage *
  page46_i123
#ISCELL
  standard offpage *
  page46_i124
#ISCELL
  standard offpage *
  page46_i125
#ISCELL
  standard offpage *
  page46_i126
#ISCELL
  standard offpage *
  page46_i127
#CELL
  pure_quanta q_res *
  page46_i132
#ISCELL
  logical_power universal_power *
  page46_i133
#CELL
  pure_quanta q_res *
  page46_i134
#ISCELL
  logical_power universal_power *
  page46_i135
#CELL
  pure_quanta q_res *
  page46_i136
#CELL
  pure_quanta q_res *
  page46_i137
#ISCELL
  logical_power universal_power *
  page46_i138
#CELL
  pure_quanta q_res *
  page46_i139
#CELL
  pure_quanta q_res *
  page46_i140
#ISCELL
  standard offpage *
  page46_i141
#ISCELL
  standard offpage *
  page46_i143
#ISCELL
  logical_power universal_power *
  page46_i145
#ISCELL
  logical_power universal_power *
  page46_i146
#CELL
  pure_quanta q_res *
  page46_i147
#CELL
  pure_quanta sconn11_9192031111lf *
  page46_i56
#CELL
  pure_quanta q_res *
  page46_i58
#ISCELL
  standard offpage *
  page46_i59
#CELL
  pure_quanta q_res *
  page46_i60
#CELL
  pure_quanta q_res *
  page46_i65
#ISCELL
  standard offpage *
  page46_i66
#CELL
  pure_quanta q_cap *
  page46_i67
#ISCELL
  logical_power universal_power *
  page46_i68
#CELL
  pure_quanta q_cap *
  page46_i69
#ISCELL
  logical_power universal_gnd *
  page46_i70
#ISCELL
  logical_power universal_gnd *
  page46_i71
#ISCELL
  standard offpage *
  page46_i72
#ISCELL
  standard offpage *
  page46_i73
#CELL
  pure_quanta q_res *
  page46_i74
#CELL
  pure_quanta q_res *
  page46_i75
#ISCELL
  logical_power universal_power *
  page46_i77
#CELL
  pure_quanta q_res *
  page46_i78
#ISCELL
  standard offpage *
  page46_i81
#ISCELL
  standard offpage *
  page46_i82
#ISCELL
  standard offpage *
  page46_i83
#ISCELL
  logical_power universal_power *
  page46_i97
#CELL
  pure_quanta q_res *
  page46_i98
#ISCELL
  standard offpage *
  page46_i99
